FILE_TYPE = CONNECTIVITY;
{Allegro Design Entry HDL 17.2-2016 S081 (4005846) 1/11/2022}
"PAGE_NUMBER" = 211;
0"NC";
1"FM_CPU0_SKTOCC_LVT3_N";
2"FM_CPU1_SKTOCC_LVT3_N";
3"PWRGD_P3V3_AUX";
4"SGPIO_DEBUG_PLD_DIN";
5"SGPIO_BMC_CLK";
6"SGPIO_BMC_DIN_R";
7"SGPIO_BMC_DOUT";
8"SGPIO_DEBUG_PLD_LD_N";
9"SGPIO_LD_1";
10"SGPIO_DI_1";
11"SGPIO_CLK_1";
12"SGPIO_DO_1";
13"RST_SGPIO_RESET_N_R";
14"SGPIO_BMC_LD_N";
15"IRQ_SGPIO_INTR_N_R";
16"SGPIO_DEBUG_PLD_CLK";
17"SGPIO_DEBUG_PLD_DOUT";
18"IRQ_SGPIO_INTR_N";
19"RST_SGPIO_RESET_N";
20"FM_PVCCFA_EHV_FIVRA_CPU1_R_EN";
21"PWRGD_P3V3_AUX_PDB";
22"PWRGD_P3V3_AUX_PLD";
23"PWRGD_CPUPWRGD_LVC1_R";
24"PWRGD_SYS_PWROK";
25"FM_PVCCFA_EHV_CPU1_R_EN";
26"FM_PVCCIN_CPU1_R_EN";
27"FM_CPU1_SKTOCC_LVT3_PLD_N";
28"FM_CPU0_SKTOCC_LVT3_PLD_N";
29"PWRGD_PCH_PWROK_R";
30"PWRGD_P1V8_PCH_AUX_PLD";
31"PWRGD_SYS_PWROK_R";
32"PWRGD_CPUPWRGD_LVC1";
33"PWRGD_PCH_PWROK";
34"RST_PFR_OVR_SRTC_R";
35"RST_PFR_OVR_SRTC";
36"RST_PFR_OVR_RTC_R";
37"RST_PFR_OVR_RTC";
38"SGPIO_DO_0";
39"PWRGD_P1V8_PCH_AUX";
40"FM_PVCCFA_EHV_FIVRA_CPU1_EN";
41"FM_PVCCIN_CPU1_EN";
42"FM_PVCCFA_EHV_FIVRA_CPU0_R_EN";
43"FM_PVCCFA_EHV_FIVRA_CPU0_EN";
44"FM_PVCCINFAON_CPU0_R_EN";
45"FM_PVCCINFAON_CPU0_EN";
46"FM_PVCCFA_EHV_CPU0_R_EN";
47"FM_PVCCFA_EHV_CPU0_EN";
48"SGPIO_LD_0";
49"SGPIO_DI_0";
50"SGPIO_CLK_0";
51"FM_PVCCFA_EHV_CPU1_EN";
52"FM_PVCCINFAON_CPU1_R_EN";
53"FM_PVCCINFAON_CPU1_EN";
54"FM_PVCCIN_CPU0_R_EN";
55"FM_PVCCIN_CPU0_EN";
%"Q_RES"
"1","(-1625,3975)","0","pure_quanta","I10";
;
PART_NUMBER"CS03322FB03"
TOLERANCE"1%"
VALUE"33.2"
PACK_TYPE"0402LF"
MATERIAL"CHIP"
WATTAGE"1/16W"
$LOCATION"R982"
CDS_LIB"pure_quanta"
CDS_LOCATION"R982"
$SEC"1"
CDS_SEC"1";
"B"
$PN"2"47;
"A"
$PN"1"46;
%"Q_RES"
"1","(3025,2150)","0","pure_quanta","I110";
;
PART_NUMBER"CS03322FB03"
TOLERANCE"1%"
PACK_TYPE"0402LF"
WATTAGE"1/16W"
VALUE"33.2"
MATERIAL"CHIP"
$LOCATION"R1811"
CDS_LIB"pure_quanta"
CDS_LOCATION"R1811"
$SEC"1"
CDS_SEC"1";
"B"
$PN"2"13;
"A"
$PN"1"19;
%"Q_RES"
"1","(3025,1925)","0","pure_quanta","I111";
;
PART_NUMBER"CS03322FB03"
WATTAGE"1/16W"
PACK_TYPE"0402LF"
MATERIAL"CHIP"
VALUE"33.2"
TOLERANCE"1%"
$LOCATION"R1812"
CDS_LIB"pure_quanta"
CDS_LOCATION"R1812"
$SEC"1"
CDS_SEC"1";
"B"
$PN"2"15;
"A"
$PN"1"18;
%"Q_RES"
"1","(3000,-375)","0","pure_quanta","I122";
;
PART_NUMBER"CS03322FB03"
VALUE"33.2"
WATTAGE"1/16W"
PACK_TYPE"0402LF"
TOLERANCE"1%"
MATERIAL"CHIP"
$LOCATION"R1843"
CDS_LIB"pure_quanta"
CDS_LOCATION"R1843"
$SEC"1"
CDS_SEC"1";
"B"
$PN"2"37;
"A"
$PN"1"36;
%"Q_RES"
"1","(3000,-600)","0","pure_quanta","I123";
;
PART_NUMBER"CS03322FB03"
WATTAGE"1/16W"
PACK_TYPE"0402LF"
TOLERANCE"1%"
VALUE"33.2"
MATERIAL"CHIP"
$LOCATION"R1844"
CDS_LIB"pure_quanta"
CDS_LOCATION"R1844"
$SEC"1"
CDS_SEC"1";
"B"
$PN"2"35;
"A"
$PN"1"34;
%"Q_RES"
"1","(-1625,350)","0","pure_quanta","I127";
;
PART_NUMBER"CS03322FB03"
VALUE"33.2"
WATTAGE"1/16W"
PACK_TYPE"0402LF"
TOLERANCE"1%"
MATERIAL"CHIP"
$LOCATION"R1919"
CDS_LIB"pure_quanta"
CDS_LOCATION"R1919"
$SEC"1"
CDS_SEC"1";
"B"
$PN"2"22;
"A"
$PN"1"3;
%"Q_RES"
"1","(-1650,150)","0","pure_quanta","I129";
;
PART_NUMBER"CS03322FB03"
MATERIAL"CHIP"
VALUE"33.2"
TOLERANCE"1%"
PACK_TYPE"0402LF"
WATTAGE"1/16W"
$LOCATION"R4267"
CDS_LIB"pure_quanta"
CDS_LOCATION"R4267"
$SEC"1"
CDS_SEC"1";
"B"
$PN"2"21;
"A"
$PN"1"3;
%"Q_RES"
"1","(-1625,3725)","0","pure_quanta","I13";
;
PART_NUMBER"CS03322FB03"
TOLERANCE"1%"
VALUE"33.2"
WATTAGE"1/16W"
MATERIAL"CHIP"
PACK_TYPE"0402LF"
$LOCATION"R983"
CDS_LIB"pure_quanta"
CDS_LOCATION"R983"
$SEC"1"
CDS_SEC"1";
"B"
$PN"2"45;
"A"
$PN"1"44;
%"Q_RES"
"1","(-1625,3500)","0","pure_quanta","I15";
;
PART_NUMBER"CS03322FB03"
TOLERANCE"1%"
VALUE"33.2"
WATTAGE"1/16W"
PACK_TYPE"0402LF"
MATERIAL"CHIP"
$LOCATION"R984"
CDS_LIB"pure_quanta"
CDS_LOCATION"R984"
$SEC"1"
CDS_SEC"1";
"B"
$PN"2"43;
"A"
$PN"1"42;
%"Q_RES"
"1","(-1625,3075)","0","pure_quanta","I21";
;
PART_NUMBER"CS03322FB03"
TOLERANCE"1%"
VALUE"33.2"
PACK_TYPE"0402LF"
MATERIAL"CHIP"
WATTAGE"1/16W"
$LOCATION"R985"
CDS_LIB"pure_quanta"
CDS_LOCATION"R985"
$SEC"1"
CDS_SEC"1";
"B"
$PN"2"41;
"A"
$PN"1"26;
%"Q_RES"
"1","(-1625,2375)","0","pure_quanta","I23";
;
PART_NUMBER"CS03322FB03"
TOLERANCE"1%"
VALUE"33.2"
PACK_TYPE"0402LF"
MATERIAL"CHIP"
WATTAGE"1/16W"
$LOCATION"R988"
CDS_LIB"pure_quanta"
CDS_LOCATION"R988"
$SEC"1"
CDS_SEC"1";
"B"
$PN"2"40;
"A"
$PN"1"20;
%"Q_RES"
"1","(-1625,2600)","0","pure_quanta","I24";
;
PART_NUMBER"CS03322FB03"
TOLERANCE"1%"
VALUE"33.2"
MATERIAL"CHIP"
WATTAGE"1/16W"
PACK_TYPE"0402LF"
$LOCATION"R987"
CDS_LIB"pure_quanta"
CDS_LOCATION"R987"
$SEC"1"
CDS_SEC"1";
"B"
$PN"2"53;
"A"
$PN"1"52;
%"Q_RES"
"1","(-1625,2850)","0","pure_quanta","I25";
;
PART_NUMBER"CS03322FB03"
TOLERANCE"1%"
VALUE"33.2"
MATERIAL"CHIP"
PACK_TYPE"0402LF"
WATTAGE"1/16W"
$LOCATION"R986"
CDS_LIB"pure_quanta"
CDS_LOCATION"R986"
$SEC"1"
CDS_SEC"1";
"B"
$PN"2"51;
"A"
$PN"1"25;
%"Q_RES"
"1","(-1625,1725)","0","pure_quanta","I44";
;
PART_NUMBER"CS03322FB03"
WATTAGE"1/16W"
VALUE"33.2"
PACK_TYPE"0402LF"
MATERIAL"CHIP"
TOLERANCE"1%"
$LOCATION"R1423"
CDS_LIB"pure_quanta"
CDS_LOCATION"R1423"
$SEC"1"
CDS_SEC"1";
"B"
$PN"2"24;
"A"
$PN"1"31;
%"Q_RES"
"1","(-1625,1500)","0","pure_quanta","I48";
;
PART_NUMBER"CS03322FB03"
PACK_TYPE"0402LF"
MATERIAL"CHIP"
WATTAGE"1/16W"
VALUE"33.2"
TOLERANCE"1%"
$LOCATION"R1442"
CDS_LIB"pure_quanta"
CDS_LOCATION"R1442"
$SEC"1"
CDS_SEC"1";
"B"
$PN"2"33;
"A"
$PN"1"29;
%"Q_RES"
"1","(-1625,1250)","0","pure_quanta","I49";
;
PART_NUMBER"CS03322FB03"
TOLERANCE"1%"
PACK_TYPE"0402LF"
MATERIAL"CHIP"
WATTAGE"1/16W"
VALUE"33.2"
$LOCATION"R1443"
CDS_LIB"pure_quanta"
CDS_LOCATION"R1443"
$SEC"1"
CDS_SEC"1";
"B"
$PN"2"23;
"A"
$PN"1"32;
%"Q_RES"
"1","(-1625,1025)","0","pure_quanta","I54";
;
PART_NUMBER"CS03322FB03"
WATTAGE"1/16W"
MATERIAL"CHIP"
VALUE"33.2"
TOLERANCE"1%"
PACK_TYPE"0402LF"
$LOCATION"R1444"
CDS_LIB"pure_quanta"
CDS_LOCATION"R1444"
$SEC"1"
CDS_SEC"1";
"B"
$PN"2"30;
"A"
$PN"1"39;
%"Q_RES"
"1","(-1625,-600)","0","pure_quanta","I62";
;
PART_NUMBER"CS03322FB03"
WATTAGE"1/16W"
VALUE"33.2"
TOLERANCE"1%"
PACK_TYPE"0402LF"
MATERIAL"CHIP"
$LOCATION"R1448"
CDS_LIB"pure_quanta"
CDS_LOCATION"R1448"
$SEC"1"
CDS_SEC"1";
"B"
$PN"2"27;
"A"
$PN"1"2;
%"Q_RES"
"1","(-1625,-375)","0","pure_quanta","I68";
;
PART_NUMBER"CS03322FB03"
VALUE"33.2"
TOLERANCE"1%"
PACK_TYPE"0402LF"
MATERIAL"CHIP"
WATTAGE"1/16W"
$LOCATION"R1447"
CDS_LIB"pure_quanta"
CDS_LOCATION"R1447"
$SEC"1"
CDS_SEC"1";
"B"
$PN"2"28;
"A"
$PN"1"1;
%"Q_RES"
"1","(3000,4200)","0","pure_quanta","I81";
;
PART_NUMBER"CS03322FB03"
MATERIAL"CHIP"
TOLERANCE"1%"
VALUE"33.2"
WATTAGE"1/16W"
PACK_TYPE"0402LF"
$LOCATION"R1751"
CDS_LIB"pure_quanta"
CDS_LOCATION"R1751"
$SEC"1"
CDS_SEC"1";
"B"
$PN"2"17;
"A"
$PN"1"38;
%"Q_RES"
"1","(3000,3975)","0","pure_quanta","I82";
;
PART_NUMBER"CS03322FB03"
MATERIAL"CHIP"
TOLERANCE"1%"
VALUE"33.2"
WATTAGE"1/16W"
PACK_TYPE"0402LF"
$LOCATION"R1752"
CDS_LIB"pure_quanta"
CDS_LOCATION"R1752"
$SEC"1"
CDS_SEC"1";
"B"
$PN"2"16;
"A"
$PN"1"50;
%"Q_RES"
"1","(3000,3725)","0","pure_quanta","I84";
;
PART_NUMBER"CS03322FB03"
MATERIAL"CHIP"
TOLERANCE"1%"
VALUE"33.2"
WATTAGE"1/16W"
PACK_TYPE"0402LF"
$LOCATION"R1753"
CDS_LIB"pure_quanta"
CDS_LOCATION"R1753"
$SEC"1"
CDS_SEC"1";
"B"
$PN"2"4;
"A"
$PN"1"49;
%"Q_RES"
"1","(3000,3500)","0","pure_quanta","I88";
;
PART_NUMBER"CS03322FB03"
MATERIAL"CHIP"
VALUE"33.2"
TOLERANCE"1%"
WATTAGE"1/16W"
PACK_TYPE"0402LF"
$LOCATION"R1754"
CDS_LIB"pure_quanta"
CDS_LOCATION"R1754"
$SEC"1"
CDS_SEC"1";
"B"
$PN"2"8;
"A"
$PN"1"48;
%"Q_RES"
"1","(-1625,4200)","0","pure_quanta","I9";
;
PART_NUMBER"CS03322FB03"
TOLERANCE"1%"
VALUE"33.2"
PACK_TYPE"0402LF"
MATERIAL"CHIP"
WATTAGE"1/16W"
$LOCATION"R981"
CDS_LIB"pure_quanta"
CDS_LOCATION"R981"
$SEC"1"
CDS_SEC"1";
"B"
$PN"2"55;
"A"
$PN"1"54;
%"Q_RES"
"1","(3025,2375)","0","pure_quanta","I91";
;
PART_NUMBER"CS03322FB03"
WATTAGE"1/16W"
TOLERANCE"1%"
VALUE"33.2"
PACK_TYPE"0402LF"
MATERIAL"CHIP"
$LOCATION"R1758"
CDS_LIB"pure_quanta"
CDS_LOCATION"R1758"
$SEC"1"
CDS_SEC"1";
"B"
$PN"2"14;
"A"
$PN"1"9;
%"Q_RES"
"1","(3025,3075)","0","pure_quanta","I96";
;
PART_NUMBER"CS03322FB03"
TOLERANCE"1%"
MATERIAL"CHIP"
PACK_TYPE"0402LF"
WATTAGE"1/16W"
VALUE"33.2"
$LOCATION"R1755"
CDS_LIB"pure_quanta"
CDS_LOCATION"R1755"
$SEC"1"
CDS_SEC"1";
"B"
$PN"2"7;
"A"
$PN"1"12;
%"Q_RES"
"1","(3025,2850)","0","pure_quanta","I98";
;
PART_NUMBER"CS03322FB03"
WATTAGE"1/16W"
MATERIAL"CHIP"
PACK_TYPE"0402LF"
VALUE"33.2"
TOLERANCE"1%"
$LOCATION"R1756"
CDS_LIB"pure_quanta"
CDS_LOCATION"R1756"
$SEC"1"
CDS_SEC"1";
"B"
$PN"2"5;
"A"
$PN"1"11;
%"Q_RES"
"1","(3025,2600)","0","pure_quanta","I99";
;
PART_NUMBER"CS03322FB03"
MATERIAL"CHIP"
PACK_TYPE"0402LF"
WATTAGE"1/16W"
VALUE"33.2"
TOLERANCE"1%"
$LOCATION"R1757"
CDS_LIB"pure_quanta"
CDS_LOCATION"R1757"
$SEC"1"
CDS_SEC"1";
"B"
$PN"2"6;
"A"
$PN"1"10;
END.
